.HEADER
BOARD_FILE 3.0 "Creo Elements/Pro 5.0 M210" 2017/02/09.15:57:36 3
16347-SC                                MM        
.END_HEADER
.BOARD_OUTLINE  MCAD
1.00000             
         0           185.00000             0.00000             0.00000
         0           185.00000             9.00000             0.00000
         0           184.00000            10.00000            90.00000
         0           176.35000            10.00000             0.00000
         0           175.35000            11.00000           -90.00000
         0           175.35000            16.20000             0.00000
         0           174.35000            17.20000            90.00000
         0           168.35000            17.20000             0.00000
         0           167.35000            16.20000            90.00000
         0           167.35000            11.00000             0.00000
         0           166.35000            10.00000           -90.00000
         0           144.80000            10.00000             0.00000
         0           143.80000            11.00000           -90.00000
         0           143.80000            16.20000             0.00000
         0           142.80000            17.20000            90.00000
         0           136.80000            17.20000             0.00000
         0           135.80000            16.20000            90.00000
         0           135.80000            11.00000             0.00000
         0           134.80000            10.00000           -90.00000
         0           113.25000            10.00000             0.00000
         0           112.25000            11.00000           -90.00000
         0           112.25000            16.20000             0.00000
         0           111.25000            17.20000            90.00000
         0           105.25000            17.20000             0.00000
         0           104.25000            16.20000            90.00000
         0           104.25000            11.00000             0.00000
         0           103.25000            10.00000           -90.00000
         0            81.70000            10.00000             0.00000
         0            80.70000            11.00000           -90.00000
         0            80.70000            16.20000             0.00000
         0            79.70000            17.20000            90.00000
         0            73.70000            17.20000             0.00000
         0            72.70000            16.20000            90.00000
         0            72.70000            11.00000             0.00000
         0            71.70000            10.00000           -90.00000
         0            58.65000            10.00000             0.00000
         0            57.65000            11.00000           -90.00000
         0            57.65000            17.20000             0.00000
         0            56.65000            18.20000            90.00000
         0            41.65000            18.20000             0.00000
         0            40.65000            17.20000            90.00000
         0            40.65000            11.00000             0.00000
         0            39.65000            10.00000           -90.00000
         0            18.60000            10.00000             0.00000
         0            17.60000            11.00000           -90.00000
         0            17.60000            16.20000             0.00000
         0            16.60000            17.20000            90.00000
         0            10.60000            17.20000             0.00000
         0             9.60000            16.20000            90.00000
         0             9.60000            11.00000             0.00000
         0             8.60000            10.00000           -90.00000
         0             1.00000            10.00000             0.00000
         0             0.00000             9.00000            90.00000
         0             0.00000             0.00000             0.00000
         0             1.00000            -1.00000            90.00000
         0           184.00000            -1.00000             0.00000
         0           185.00000             0.00000            90.00000
         1           125.40000             5.00000             0.00000
         1           122.85000             5.00000          -180.00000
         1           125.40000             5.00000          -180.00000
         2            77.97500             5.00000             0.00000
         2            75.42500             5.00000          -180.00000
         2            77.97500             5.00000          -180.00000
         3           182.15000             5.00000             0.00000
         3           179.60000             5.00000          -180.00000
         3           182.15000             5.00000          -180.00000
         4             5.40000             5.00000             0.00000
         4             2.85000             5.00000          -180.00000
         4             5.40000             5.00000          -180.00000
         5            13.57500             5.00000             0.00000
         5            10.67500             5.00000          -180.00000
         5            13.57500             5.00000          -180.00000
         6           174.32500             5.00000             0.00000
         6           171.42500             5.00000          -180.00000
         6           174.32500             5.00000          -180.00000
.END_BOARD_OUTLINE
.DRILLED_HOLES
.END_DRILLED_HOLES
.PLACE_KEEPOUT      UNOWNED
TOP 0.00000        
         0           121.12500             5.00000             0.00000
         0           127.12500             5.00000           180.00000
         0           121.12500             5.00000           180.00000
.END_PLACE_KEEPOUT
.PLACE_KEEPOUT      UNOWNED
TOP 0.00000        
         0            73.70000             5.00000             0.00000
         0            79.70000             5.00000           180.00000
         0            73.70000             5.00000           180.00000
.END_PLACE_KEEPOUT
.PLACE_KEEPOUT      UNOWNED
TOP 0.00000        
         0           183.87500             5.00000             0.00000
         0           177.87500             5.00000           180.00000
         0           183.87500             5.00000           180.00000
.END_PLACE_KEEPOUT
.PLACE_KEEPOUT      UNOWNED
TOP 0.00000        
         0             1.12500             5.00000             0.00000
         0             7.12500             5.00000           180.00000
         0             1.12500             5.00000           180.00000
.END_PLACE_KEEPOUT
.PLACE_KEEPOUT      UNOWNED
TOP 0.20000        
         0             0.00000             9.00000             0.00000
         0             0.00000             0.00000             0.00000
         0             1.00000            -1.00000            90.00000
         0           184.00000            -1.00000             0.00000
         0           185.00000             0.00000            90.00000
         0           185.00000             9.00000             0.00000
         0           184.00000            10.00000            90.00000
         0           176.35000            10.00000             0.00000
         0           175.35000            11.00000           -90.00000
         0           175.35000            16.20000             0.00000
         0           174.35000            17.20000            90.00000
         0           168.35000            17.20000             0.00000
         0           167.35000            16.20000            90.00000
         0           167.35000            11.00000             0.00000
         0           166.35000            10.00000           -90.00000
         0           144.80000            10.00000             0.00000
         0           143.80000            11.00000           -90.00000
         0           143.80000            16.20000             0.00000
         0           142.80000            17.20000            90.00000
         0           136.80000            17.20000             0.00000
         0           135.80000            16.20000            90.00000
         0           135.80000            11.00000             0.00000
         0           134.80000            10.00000           -90.00000
         0           113.25000            10.00000             0.00000
         0           112.25000            11.00000           -90.00000
         0           112.25000            16.20000             0.00000
         0           111.25000            17.20000            90.00000
         0           105.25000            17.20000             0.00000
         0           104.25000            16.20000            90.00000
         0           104.25000            11.00000             0.00000
         0           103.25000            10.00000           -90.00000
         0            81.70000            10.00000             0.00000
         0            80.70000            11.00000           -90.00000
         0            80.70000            16.20000             0.00000
         0            79.70000            17.20000            90.00000
         0            73.70000            17.20000             0.00000
         0            72.70000            16.20000            90.00000
         0            72.70000            11.00000             0.00000
         0            71.70000            10.00000           -90.00000
         0            58.65000            10.00000             0.00000
         0            57.65000            11.00000           -90.00000
         0            57.65000            17.20000             0.00000
         0            56.65000            18.20000            90.00000
         0            41.65000            18.20000             0.00000
         0            40.65000            17.20000            90.00000
         0            40.65000            11.00000             0.00000
         0            39.65000            10.00000           -90.00000
         0            18.60000            10.00000             0.00000
         0            17.60000            11.00000           -90.00000
         0            17.60000            16.20000             0.00000
         0            16.60000            17.20000            90.00000
         0            10.60000            17.20000             0.00000
         0             9.60000            16.20000            90.00000
         0             9.60000            11.00000             0.00000
         0             8.60000            10.00000           -90.00000
         0             1.00000            10.00000             0.00000
         0             0.00000             9.00000            90.00000
.END_PLACE_KEEPOUT
.PLACE_KEEPOUT      UNOWNED
TOP 0.20000        
         0           121.12500             5.00000             0.00000
         0           127.12500             5.00000           180.00000
         0           121.12500             5.00000           180.00000
.END_PLACE_KEEPOUT
.PLACE_KEEPOUT      UNOWNED
TOP 0.20000        
         0            73.70000             5.00000             0.00000
         0            79.70000             5.00000           180.00000
         0            73.70000             5.00000           180.00000
.END_PLACE_KEEPOUT
.PLACE_KEEPOUT      UNOWNED
TOP 0.20000        
         0           177.87500             5.00000             0.00000
         0           183.87500             5.00000           180.00000
         0           177.87500             5.00000           180.00000
.END_PLACE_KEEPOUT
.PLACE_KEEPOUT      UNOWNED
TOP 0.20000        
         0             7.12500             5.00000             0.00000
         0             1.12500             5.00000           180.00000
         0             7.12500             5.00000           180.00000
.END_PLACE_KEEPOUT
.PLACE_KEEPOUT      UNOWNED
TOP 0.20000        
         0           174.32500             5.00000             0.00000
         0           171.42500             5.00000           180.00000
         0           174.32500             5.00000           180.00000
.END_PLACE_KEEPOUT
.PLACE_KEEPOUT      UNOWNED
TOP 0.20000        
         0            13.57500             5.00000             0.00000
         0            10.67500             5.00000           180.00000
         0            13.57500             5.00000           180.00000
.END_PLACE_KEEPOUT
.PLACE_KEEPOUT      UNOWNED
BOTTOM 0.00000        
         0            73.70000             5.00000             0.00000
         0            79.70000             5.00000          -180.00000
         0            73.70000             5.00000          -180.00000
.END_PLACE_KEEPOUT
.PLACE_KEEPOUT      UNOWNED
BOTTOM 0.00000        
         0           127.12500             5.00000             0.00000
         0           121.12500             5.00000          -180.00000
         0           127.12500             5.00000          -180.00000
.END_PLACE_KEEPOUT
.PLACE_KEEPOUT      UNOWNED
BOTTOM 0.00000        
         0             7.12500             5.00000             0.00000
         0             1.12500             5.00000          -180.00000
         0             7.12500             5.00000          -180.00000
.END_PLACE_KEEPOUT
.PLACE_KEEPOUT      UNOWNED
BOTTOM 0.00000        
         0           183.87500             5.00000             0.00000
         0           177.87500             5.00000          -180.00000
         0           183.87500             5.00000          -180.00000
.END_PLACE_KEEPOUT
.PLACE_KEEPOUT      UNOWNED
BOTTOM 0.00000        
         0            57.45000            -1.00000             0.00000
         0            57.45000             9.60000             0.00000
         0            40.85000             9.60000             0.00000
         0            40.85000            -1.00000             0.00000
         0            57.45000            -1.00000             0.00000
.END_PLACE_KEEPOUT
.PLACE_KEEPOUT      UNOWNED
BOTTOM 3.00000        
         0           144.80000            10.00000             0.00000
         0           143.80000            11.00000           -90.00000
         0           143.80000            16.20000             0.00000
         0           142.80000            17.20000            90.00000
         0           136.80000            17.20000             0.00000
         0           135.80000            16.20000            90.00000
         0           135.80000            11.00000             0.00000
         0           134.80000            10.00000           -90.00000
         0           113.25000            10.00000             0.00000
         0           112.25000            11.00000           -90.00000
         0           112.25000            16.20000             0.00000
         0           111.25000            17.20000            90.00000
         0           105.25000            17.20000             0.00000
         0           104.25000            16.20000            90.00000
         0           104.25000            11.00000             0.00000
         0           103.25000            10.00000           -90.00000
         0            81.70000            10.00000             0.00000
         0            80.70000            11.00000           -90.00000
         0            80.70000            16.20000             0.00000
         0            79.70000            17.20000            90.00000
         0            73.70000            17.20000             0.00000
         0            72.70000            16.20000            90.00000
         0            72.70000            11.00000             0.00000
         0            71.70000            10.00000           -90.00000
         0            58.65000            10.00000             0.00000
         0            57.65000            11.00000           -90.00000
         0            57.65000            17.20000             0.00000
         0            56.65000            18.20000            90.00000
         0            41.65000            18.20000             0.00000
         0            40.65000            17.20000            90.00000
         0            40.65000            11.00000             0.00000
         0            39.65000            10.00000           -90.00000
         0            18.60000            10.00000             0.00000
         0            17.60000            11.00000           -90.00000
         0            17.60000            16.20000             0.00000
         0            16.60000            17.20000            90.00000
         0            10.60000            17.20000             0.00000
         0             9.60000            16.20000            90.00000
         0             9.60000            11.00000             0.00000
         0             8.60000            10.00000           -90.00000
         0             1.00000            10.00000             0.00000
         0             0.00000             9.00000            90.00000
         0             0.00000             0.00000             0.00000
         0             1.00000            -1.00000            90.00000
         0            40.85000            -1.00000             0.00000
         0            40.85000             9.60000             0.00000
         0            57.45000             9.60000             0.00000
         0            57.45000            -1.00000             0.00000
         0           184.00000            -1.00000             0.00000
         0           185.00000             0.00000            90.00000
         0           185.00000             9.00000             0.00000
         0           184.00000            10.00000            90.00000
         0           176.35000            10.00000             0.00000
         0           175.35000            11.00000           -90.00000
         0           175.35000            16.20000             0.00000
         0           174.35000            17.20000            90.00000
         0           168.35000            17.20000             0.00000
         0           167.35000            16.20000            90.00000
         0           167.35000            11.00000             0.00000
         0           166.35000            10.00000           -90.00000
         0           144.80000            10.00000             0.00000
.END_PLACE_KEEPOUT
.PLACE_KEEPOUT      UNOWNED
BOTTOM 3.00000        
         0            79.70000             5.00000             0.00000
         0            73.70000             5.00000          -180.00000
         0            79.70000             5.00000          -180.00000
.END_PLACE_KEEPOUT
.PLACE_KEEPOUT      UNOWNED
BOTTOM 3.00000        
         0             1.12500             5.00000             0.00000
         0             7.12500             5.00000          -180.00000
         0             1.12500             5.00000          -180.00000
.END_PLACE_KEEPOUT
.PLACE_KEEPOUT      UNOWNED
BOTTOM 3.00000        
         0           177.87500             5.00000             0.00000
         0           183.87500             5.00000          -180.00000
         0           177.87500             5.00000          -180.00000
.END_PLACE_KEEPOUT
.PLACE_KEEPOUT      UNOWNED
BOTTOM 3.00000        
         0           121.12500             5.00000             0.00000
         0           127.12500             5.00000          -180.00000
         0           121.12500             5.00000          -180.00000
.END_PLACE_KEEPOUT
.PLACE_KEEPOUT      UNOWNED
BOTTOM 3.00000        
         0            10.67500             5.00000             0.00000
         0            13.57500             5.00000          -180.00000
         0            10.67500             5.00000          -180.00000
.END_PLACE_KEEPOUT
.PLACE_KEEPOUT      UNOWNED
BOTTOM 3.00000        
         0           171.42500             5.00000             0.00000
         0           174.32500             5.00000          -180.00000
         0           171.42500             5.00000          -180.00000
.END_PLACE_KEEPOUT
.ROUTE_KEEPOUT  UNOWNED
TOP
         0           121.12500             5.00000             0.00000
         0           127.12500             5.00000           180.00000
         0           121.12500             5.00000           180.00000
.END_ROUTE_KEEPOUT
.ROUTE_KEEPOUT  UNOWNED
TOP
         0            73.70000             5.00000             0.00000
         0            79.70000             5.00000           180.00000
         0            73.70000             5.00000           180.00000
.END_ROUTE_KEEPOUT
.ROUTE_KEEPOUT  UNOWNED
TOP
         0           183.87500             5.00000             0.00000
         0           177.87500             5.00000           180.00000
         0           183.87500             5.00000           180.00000
.END_ROUTE_KEEPOUT
.ROUTE_KEEPOUT  UNOWNED
TOP
         0             7.12500             5.00000             0.00000
         0             1.12500             5.00000           180.00000
         0             7.12500             5.00000           180.00000
.END_ROUTE_KEEPOUT
.ROUTE_KEEPOUT  UNOWNED
BOTTOM
         0            79.70000             5.00000             0.00000
         0            73.70000             5.00000          -180.00000
         0            79.70000             5.00000          -180.00000
.END_ROUTE_KEEPOUT
.ROUTE_KEEPOUT  UNOWNED
BOTTOM
         0           127.12500             5.00000             0.00000
         0           121.12500             5.00000          -180.00000
         0           127.12500             5.00000          -180.00000
.END_ROUTE_KEEPOUT
.ROUTE_KEEPOUT  UNOWNED
BOTTOM
         0             7.12500             5.00000             0.00000
         0             1.12500             5.00000          -180.00000
         0             7.12500             5.00000          -180.00000
.END_ROUTE_KEEPOUT
.ROUTE_KEEPOUT  UNOWNED
BOTTOM
         0           125.40000             5.00000             0.00000
         0           122.85000             5.00000          -180.00000
         0           125.40000             5.00000          -180.00000
.END_ROUTE_KEEPOUT
.ROUTE_KEEPOUT  UNOWNED
BOTTOM
         0           183.87500             5.00000             0.00000
         0           177.87500             5.00000          -180.00000
         0           183.87500             5.00000          -180.00000
.END_ROUTE_KEEPOUT
.PLACEMENT
083_00195_0B70 083_00195_0B70 LED6          
171.35000      15.00000       0.00000        0.00000        TOP       PLACED         
083_00195_0B70 083_00195_0B70 LED5          
139.80000      15.00000       0.00000        0.00000        TOP       PLACED         
083_00195_0B70 083_00195_0B70 LED4          
108.25000      15.00000       0.00000        0.00000        TOP       PLACED         
083_00195_0B70 083_00195_0B70 LED3          
76.70000       15.00000       0.00000        0.00000        TOP       PLACED         
083_00195_0B70 083_00195_0B70 LED2          
45.15000       15.00000       0.00000        0.00000        TOP       PLACED         
083_00195_0B70 083_00195_0B70 LED1          
13.60000       15.00000       0.00000        0.00000        TOP       PLACED         
020_F0496_0020 020_F0496_0020 CN1           
49.15000       11.90000       0.00000        0.00000        BOTTOM    PLACED         
.END_PLACEMENT
